# T6G (Grand Teton) — schematic netlist excerpt (pin names and nets, part order shuffled) for the footprints in the layout excerpt that follows; sources: Cadence DE-HDL packaged netlist, KiCad conversion of 04192023_DAF0TMB3IC0_F0TG_MB_C_brd_V02_OCP.brd

R476  Q_RES  33 5% CHIP  pkg 0402LF  page 172 : A = CPU0_XTRIG_L6 ; B = HDT_CPU0_XTRIG_L6

U152  SN74AVC2T245RSWR  IC  pkg UQFN10_0-4_1-8X1-4  page 173
  DIR2  = GND
  \oe_#\  = U152_OE_N
  GND  = GND
  B2  = JTAG_CPUX_TDO
  B1  = JTAG_CPUX_TDI_R1
  VCCB  = PVDD18_S5_P0
  VCCA  = PVDD18_S5_P0
  A1  = JTAG_TDI
  A2  = JTAG_TDO_R
  DIR1  = PVDD18_S5_P0

(kicad_pcb
	(version 20260206)
	(generator "pcbnew")
	(generator_version "10.0")
	(general
		(thickness 1.6)
		(legacy_teardrops no)
	)
	(paper "A4")
	(title_block
		(title "04192023_DAF0TMB3IC0_F0TG_MB_C_brd_V02_OCP.brd")
		(comment 1 "Grand Teton / footprints 3941-3942 of 8354")
	)
	(layers
		(0 "F.Cu" signal "TOP")
		(4 "In1.Cu" signal "GND")
		(6 "In2.Cu" signal "IN1")
		(8 "In3.Cu" signal "GND1")
		(10 "In4.Cu" signal "IN2")
		(12 "In5.Cu" signal "GND2")
		(14 "In6.Cu" signal "IN3")
		(16 "In7.Cu" signal "GND3")
		(18 "In8.Cu" signal "VCC")
		(20 "In9.Cu" signal "VCC1")
		(22 "In10.Cu" signal "GND4")
		(24 "In11.Cu" signal "IN4")
		(26 "In12.Cu" signal "GND5")
		(28 "In13.Cu" signal "IN5")
		(30 "In14.Cu" signal "GND6")
		(32 "In15.Cu" signal "IN6")
		(34 "In16.Cu" signal "GND7")
		(2 "B.Cu" signal "BOTTOM")
		(9 "F.Adhes" user "F.Adhesive")
		(11 "B.Adhes" user "B.Adhesive")
		(13 "F.Paste" user "Package Geometry/Pastemask Top")
		(15 "B.Paste" user "Package Geometry/Pastemask Bottom")
		(5 "F.SilkS" user "Ref Des/Silkscreen Top")
		(7 "B.SilkS" user "Ref Des/Silkscreen Bottom")
		(1 "F.Mask" user "Board Geometry/Soldermask Top")
		(3 "B.Mask" user "Board Geometry/Soldermask Bottom")
		(17 "Dwgs.User" user "User.Drawings")
		(19 "Cmts.User" user "User.Comments")
		(21 "Eco1.User" user "User.Eco1")
		(23 "Eco2.User" user "User.Eco2")
		(25 "Edge.Cuts" user "Board Geometry/Outline")
		(27 "Margin" user)
		(31 "F.CrtYd" user "Package Geometry/Place Bound Top")
		(29 "B.CrtYd" user "Package Geometry/Place Bound Bottom")
		(35 "F.Fab" user "Ref Des/Assembly Top")
		(33 "B.Fab" user "Ref Des/Assembly Bottom")
	)
	(footprint ""
		(layer "F.Cu")
		(at 403.682962 -59.4995 180)
		(property "Reference" "R476"
			(at 0 0 180)
			(layer "F.SilkS")
			(hide yes)
			(effects
				(font
					(size 1.27 1.27)
				)
			)
		)
		(property "Value" ""
			(at 0 0 180)
			(layer "F.Fab")
			(effects
				(font
					(size 1.27 1.27)
				)
			)
		)
		(duplicate_pad_numbers_are_jumpers no)
		(fp_line
			(start 0.7874 0.4064)
			(end -0.7874 0.4064)
			(stroke
				(width 0.1524)
				(type default)
			)
			(layer "F.SilkS")
		)
		(fp_line
			(start 0.7874 -0.4064)
			(end 0.7874 0.4064)
			(stroke
				(width 0.1524)
				(type default)
			)
			(layer "F.SilkS")
		)
		(fp_line
			(start -0.7874 0.4064)
			(end -0.7874 -0.4064)
			(stroke
				(width 0.1524)
				(type default)
			)
			(layer "F.SilkS")
		)
		(fp_line
			(start -0.7874 -0.4064)
			(end 0.7874 -0.4064)
			(stroke
				(width 0.1524)
				(type default)
			)
			(layer "F.SilkS")
		)
		(fp_line
			(start 0.67945 0.3048)
			(end 0.120396 0.3048)
			(stroke
				(width 0.1)
				(type default)
			)
			(layer "F.Fab")
		)
		(fp_line
			(start 0.67945 -0.3048)
			(end 0.67945 0.3048)
			(stroke
				(width 0.1)
				(type default)
			)
			(layer "F.Fab")
		)
		(fp_line
			(start 0.12065 -0.2794)
			(end 0.12065 -0.3048)
			(stroke
				(width 0.1)
				(type default)
			)
			(layer "F.Fab")
		)
		(fp_line
			(start 0.12065 -0.3048)
			(end 0.67945 -0.3048)
			(stroke
				(width 0.1)
				(type default)
			)
			(layer "F.Fab")
		)
		(fp_line
			(start 0.120396 0.3048)
			(end 0.120396 0.2794)
			(stroke
				(width 0.1)
				(type default)
			)
			(layer "F.Fab")
		)
		(fp_line
			(start 0.120396 0.2794)
			(end -0.12065 0.2794)
			(stroke
				(width 0.1)
				(type default)
			)
			(layer "F.Fab")
		)
		(fp_line
			(start -0.12065 0.3048)
			(end -0.67945 0.3048)
			(stroke
				(width 0.1)
				(type default)
			)
			(layer "F.Fab")
		)
		(fp_line
			(start -0.12065 0.2794)
			(end -0.12065 0.3048)
			(stroke
				(width 0.1)
				(type default)
			)
			(layer "F.Fab")
		)
		(fp_line
			(start -0.12065 -0.2794)
			(end 0.12065 -0.2794)
			(stroke
				(width 0.1)
				(type default)
			)
			(layer "F.Fab")
		)
		(fp_line
			(start -0.12065 -0.305054)
			(end -0.12065 -0.2794)
			(stroke
				(width 0.1)
				(type default)
			)
			(layer "F.Fab")
		)
		(fp_line
			(start -0.67945 0.3048)
			(end -0.67945 -0.305054)
			(stroke
				(width 0.1)
				(type default)
			)
			(layer "F.Fab")
		)
		(fp_line
			(start -0.67945 -0.305054)
			(end -0.12065 -0.305054)
			(stroke
				(width 0.1)
				(type default)
			)
			(layer "F.Fab")
		)
		(pad "1" smd circle
			(at -0.40005 0 180)
			(size 0 0)
			(layers "F.Cu" "F.Mask" "F.Paste")
			(net "CPU0_XTRIG_L6")
		)
		(pad "2" smd circle
			(at 0.40005 0 180)
			(size 0 0)
			(layers "F.Cu" "F.Mask" "F.Paste")
			(net "HDT_CPU0_XTRIG_L6")
		)
	)
	(footprint ""
		(layer "F.Cu")
		(at 130.067304 -54.17439 180)
		(property "Reference" "U152"
			(at -2.417064 -3.52171 0)
			(unlocked yes)
			(layer "F.SilkS")
			(effects
				(font
					(size 0.7874 0.5842)
					(thickness 0.1524)
				)
				(justify left)
			)
		)
		(property "Value" ""
			(at 0 0 180)
			(layer "F.Fab")
			(effects
				(font
					(size 1.27 1.27)
				)
			)
		)
		(duplicate_pad_numbers_are_jumpers no)
		(fp_line
			(start 1.245616 1.445768)
			(end -1.245616 1.445768)
			(stroke
				(width 0.1524)
				(type default)
			)
			(layer "F.SilkS")
		)
		(fp_line
			(start 1.245616 -1.445768)
			(end 1.245616 1.445768)
			(stroke
				(width 0.1524)
				(type default)
			)
			(layer "F.SilkS")
		)
		(fp_line
			(start -1.245616 1.445768)
			(end -1.245616 -1.445768)
			(stroke
				(width 0.1524)
				(type default)
			)
			(layer "F.SilkS")
		)
		(fp_line
			(start -1.245616 -1.445768)
			(end 1.245616 -1.445768)
			(stroke
				(width 0.1524)
				(type default)
			)
			(layer "F.SilkS")
		)
		(fp_poly
			(pts
				(xy -1.809496 -0.216662) (xy -2.317496 0.037338) (xy -2.317496 -0.470662)
			)
			(stroke
				(width 0)
				(type default)
			)
			(fill yes)
			(layer "F.SilkS")
		)
		(fp_line
			(start 0.724916 0.925068)
			(end -0.724916 0.925068)
			(stroke
				(width 0.1)
				(type default)
			)
			(layer "F.Fab")
		)
		(fp_line
			(start 0.724916 -0.925068)
			(end 0.724916 0.925068)
			(stroke
				(width 0.1)
				(type default)
			)
			(layer "F.Fab")
		)
		(fp_line
			(start -0.724916 0.925068)
			(end -0.724916 -0.925068)
			(stroke
				(width 0.1)
				(type default)
			)
			(layer "F.Fab")
		)
		(fp_line
			(start -0.724916 -0.925068)
			(end 0.724916 -0.925068)
			(stroke
				(width 0.1)
				(type default)
			)
			(layer "F.Fab")
		)
		(fp_poly
			(pts
				(xy -1.894586 -0.453898) (xy -1.894586 0.054102) (xy -1.386586 -0.199898)
			)
			(stroke
				(width 0)
				(type default)
			)
			(fill yes)
			(layer "F.Fab")
		)
		(pad "1" smd circle
			(at -0.649986 -0.199898 90)
			(size 0 0)
			(layers "F.Cu" "F.Mask" "F.Paste")
			(net "GND")
		)
		(pad "2" smd rect
			(at -0.700024 0.199898 270)
			(size 0.1778 0.8128)
			(layers "F.Cu" "F.Mask" "F.Paste")
			(net "U152_OE_N")
		)
		(pad "3" smd rect
			(at -0.40005 0.899922 180)
			(size 0.1778 0.8128)
			(layers "F.Cu" "F.Mask" "F.Paste")
			(net "GND")
		)
		(pad "4" smd rect
			(at 0 0.899922 180)
			(size 0.1778 0.8128)
			(layers "F.Cu" "F.Mask" "F.Paste")
			(net "JTAG_CPUX_TDO")
		)
		(pad "5" smd rect
			(at 0.40005 0.899922 180)
			(size 0.1778 0.8128)
			(layers "F.Cu" "F.Mask" "F.Paste")
			(net "JTAG_CPUX_TDI_R1")
		)
		(pad "6" smd rect
			(at 0.700024 0.199898 90)
			(size 0.1778 0.8128)
			(layers "F.Cu" "F.Mask" "F.Paste")
			(net "PVDD18_S5_P0")
		)
		(pad "7" smd rect
			(at 0.700024 -0.199898 90)
			(size 0.1778 0.8128)
			(layers "F.Cu" "F.Mask" "F.Paste")
			(net "PVDD18_S5_P0")
		)
		(pad "8" smd rect
			(at 0.40005 -0.899922 180)
			(size 0.1778 0.8128)
			(layers "F.Cu" "F.Mask" "F.Paste")
			(net "JTAG_TDI")
		)
		(pad "9" smd rect
			(at 0 -0.899922 180)
			(size 0.1778 0.8128)
			(layers "F.Cu" "F.Mask" "F.Paste")
			(net "JTAG_TDO_R")
		)
		(pad "10" smd rect
			(at -0.40005 -0.912622 180)
			(size 0.1778 0.7874)
			(layers "F.Cu" "F.Mask" "F.Paste")
			(net "PVDD18_S5_P0")
		)
	)
)
